(kicad_pcb
	(version 20260206)
	(generator "pcbnew")
	(generator_version "10.0")
	(general
		(thickness 1.6)
		(legacy_teardrops no)
	)
	(paper "A4")
	(title_block
		(title "01162023_DA0F0TEBIF0_F0T_Expander_BD_F_brd_V02_OCP.brd")
		(comment 1 "Grand Teton / footprints 7883-7891 of 9728")
	)
	(layers
		(0 "F.Cu" signal "TOP")
		(4 "In1.Cu" signal "GND")
		(6 "In2.Cu" signal "VCC")
		(8 "In3.Cu" signal "VCC1")
		(10 "In4.Cu" signal "GND1")
		(12 "In5.Cu" signal "IN1")
		(14 "In6.Cu" signal "GND2")
		(16 "In7.Cu" signal "IN2")
		(18 "In8.Cu" signal "GND3")
		(20 "In9.Cu" signal "IN3")
		(22 "In10.Cu" signal "GND4")
		(24 "In11.Cu" signal "IN4")
		(26 "In12.Cu" signal "GND5")
		(28 "In13.Cu" signal "IN5")
		(30 "In14.Cu" signal "GND6")
		(32 "In15.Cu" signal "IN6")
		(34 "In16.Cu" signal "GND7")
		(2 "B.Cu" signal "BOTTOM")
		(9 "F.Adhes" user "F.Adhesive")
		(11 "B.Adhes" user "B.Adhesive")
		(13 "F.Paste" user "Package Geometry/Pastemask Top")
		(15 "B.Paste" user "Package Geometry/Pastemask Bottom")
		(5 "F.SilkS" user "Ref Des/Silkscreen Top")
		(7 "B.SilkS" user "Ref Des/Silkscreen Bottom")
		(1 "F.Mask" user "Board Geometry/Soldermask Top")
		(3 "B.Mask" user "Board Geometry/Soldermask Bottom")
		(17 "Dwgs.User" user "User.Drawings")
		(19 "Cmts.User" user "User.Comments")
		(21 "Eco1.User" user "User.Eco1")
		(23 "Eco2.User" user "User.Eco2")
		(25 "Edge.Cuts" user "Board Geometry/Outline")
		(27 "Margin" user)
		(31 "F.CrtYd" user "Package Geometry/Place Bound Top")
		(29 "B.CrtYd" user "Package Geometry/Place Bound Bottom")
		(35 "F.Fab" user "Ref Des/Assembly Top")
		(33 "B.Fab" user "Ref Des/Assembly Bottom")
	)
	(footprint ""
		(layer "B.Cu")
		(at 217.235786 -214.238586 180)
		(property "Reference" "R5290"
			(at 0 0 0)
			(layer "B.SilkS")
			(hide yes)
			(effects
				(font
					(size 1.27 1.27)
				)
				(justify mirror)
			)
		)
		(property "Value" ""
			(at 0 0 0)
			(layer "B.Fab")
			(effects
				(font
					(size 1.27 1.27)
				)
				(justify mirror)
			)
		)
		(duplicate_pad_numbers_are_jumpers no)
		(fp_line
			(start 0.7874 0.4064)
			(end 0.7874 -0.4064)
			(stroke
				(width 0.1524)
				(type default)
			)
			(layer "B.SilkS")
		)
		(fp_line
			(start 0.7874 -0.4064)
			(end -0.7874 -0.4064)
			(stroke
				(width 0.1524)
				(type default)
			)
			(layer "B.SilkS")
		)
		(fp_line
			(start -0.7874 0.4064)
			(end 0.7874 0.4064)
			(stroke
				(width 0.1524)
				(type default)
			)
			(layer "B.SilkS")
		)
		(fp_line
			(start -0.7874 -0.4064)
			(end -0.7874 0.4064)
			(stroke
				(width 0.1524)
				(type default)
			)
			(layer "B.SilkS")
		)
		(fp_line
			(start 0.67945 0.3048)
			(end 0.67945 -0.305054)
			(stroke
				(width 0.1)
				(type default)
			)
			(layer "B.Fab")
		)
		(fp_line
			(start 0.67945 -0.305054)
			(end 0.12065 -0.305054)
			(stroke
				(width 0.1)
				(type default)
			)
			(layer "B.Fab")
		)
		(fp_line
			(start 0.12065 0.3048)
			(end 0.67945 0.3048)
			(stroke
				(width 0.1)
				(type default)
			)
			(layer "B.Fab")
		)
		(fp_line
			(start 0.12065 0.2794)
			(end 0.12065 0.3048)
			(stroke
				(width 0.1)
				(type default)
			)
			(layer "B.Fab")
		)
		(fp_line
			(start 0.12065 -0.2794)
			(end -0.12065 -0.2794)
			(stroke
				(width 0.1)
				(type default)
			)
			(layer "B.Fab")
		)
		(fp_line
			(start 0.12065 -0.305054)
			(end 0.12065 -0.2794)
			(stroke
				(width 0.1)
				(type default)
			)
			(layer "B.Fab")
		)
		(fp_line
			(start -0.120396 0.3048)
			(end -0.120396 0.2794)
			(stroke
				(width 0.1)
				(type default)
			)
			(layer "B.Fab")
		)
		(fp_line
			(start -0.120396 0.2794)
			(end 0.12065 0.2794)
			(stroke
				(width 0.1)
				(type default)
			)
			(layer "B.Fab")
		)
		(fp_line
			(start -0.12065 -0.2794)
			(end -0.12065 -0.3048)
			(stroke
				(width 0.1)
				(type default)
			)
			(layer "B.Fab")
		)
		(fp_line
			(start -0.12065 -0.3048)
			(end -0.67945 -0.3048)
			(stroke
				(width 0.1)
				(type default)
			)
			(layer "B.Fab")
		)
		(fp_line
			(start -0.67945 0.3048)
			(end -0.120396 0.3048)
			(stroke
				(width 0.1)
				(type default)
			)
			(layer "B.Fab")
		)
		(fp_line
			(start -0.67945 -0.3048)
			(end -0.67945 0.3048)
			(stroke
				(width 0.1)
				(type default)
			)
			(layer "B.Fab")
		)
		(pad "1" smd circle
			(at 0.40005 0)
			(size 0 0)
			(layers "B.Cu" "B.Mask" "B.Paste")
			(net "RST_BIC_SELF_HW_RST_R_N")
		)
		(pad "2" smd circle
			(at -0.40005 0)
			(size 0 0)
			(layers "B.Cu" "B.Mask" "B.Paste")
			(net "RST_BIC_SELF_HW_RST_N")
		)
	)
	(footprint ""
		(layer "B.Cu")
		(at 278.554942 -294.4749)
		(property "Reference" "C3392"
			(at 0 0 0)
			(layer "B.SilkS")
			(hide yes)
			(effects
				(font
					(size 1.27 1.27)
				)
				(justify mirror)
			)
		)
		(property "Value" ""
			(at 0 0 0)
			(layer "B.Fab")
			(effects
				(font
					(size 1.27 1.27)
				)
				(justify mirror)
			)
		)
		(duplicate_pad_numbers_are_jumpers no)
		(fp_line
			(start -0.299974 -0.150114)
			(end -0.299974 0.150114)
			(stroke
				(width 0.1)
				(type default)
			)
			(layer "B.Fab")
		)
		(fp_line
			(start -0.299974 0.150114)
			(end 0.299974 0.150114)
			(stroke
				(width 0.1)
				(type default)
			)
			(layer "B.Fab")
		)
		(fp_line
			(start 0.299974 -0.150114)
			(end -0.299974 -0.150114)
			(stroke
				(width 0.1)
				(type default)
			)
			(layer "B.Fab")
		)
		(fp_line
			(start 0.299974 0.150114)
			(end 0.299974 -0.150114)
			(stroke
				(width 0.1)
				(type default)
			)
			(layer "B.Fab")
		)
		(pad "1" smd rect
			(at 0.2667 0 180)
			(size 0.3048 0.381)
			(layers "B.Cu" "B.Mask" "B.Paste")
			(net "PCEPLL4_VDDA18_PEX2")
		)
		(pad "2" smd rect
			(at -0.2667 0 180)
			(size 0.3048 0.381)
			(layers "B.Cu" "B.Mask" "B.Paste")
			(net "GND")
		)
	)
	(footprint ""
		(layer "B.Cu")
		(at 268.102334 -364.97895 90)
		(property "Reference" "PR6612"
			(at 0 0 90)
			(layer "B.SilkS")
			(hide yes)
			(effects
				(font
					(size 1.27 1.27)
				)
				(justify mirror)
			)
		)
		(property "Value" ""
			(at 0 0 90)
			(layer "B.Fab")
			(effects
				(font
					(size 1.27 1.27)
				)
				(justify mirror)
			)
		)
		(duplicate_pad_numbers_are_jumpers no)
		(fp_line
			(start 0.7874 -0.4064)
			(end -0.7874 -0.4064)
			(stroke
				(width 0.1524)
				(type default)
			)
			(layer "B.SilkS")
		)
		(fp_line
			(start -0.7874 -0.4064)
			(end -0.7874 0.4064)
			(stroke
				(width 0.1524)
				(type default)
			)
			(layer "B.SilkS")
		)
		(fp_line
			(start 0.7874 0.4064)
			(end 0.7874 -0.4064)
			(stroke
				(width 0.1524)
				(type default)
			)
			(layer "B.SilkS")
		)
		(fp_line
			(start -0.7874 0.4064)
			(end 0.7874 0.4064)
			(stroke
				(width 0.1524)
				(type default)
			)
			(layer "B.SilkS")
		)
		(fp_line
			(start 0.67945 -0.305054)
			(end 0.12065 -0.305054)
			(stroke
				(width 0.1)
				(type default)
			)
			(layer "B.Fab")
		)
		(fp_line
			(start 0.12065 -0.305054)
			(end 0.12065 -0.2794)
			(stroke
				(width 0.1)
				(type default)
			)
			(layer "B.Fab")
		)
		(fp_line
			(start -0.12065 -0.3048)
			(end -0.67945 -0.3048)
			(stroke
				(width 0.1)
				(type default)
			)
			(layer "B.Fab")
		)
		(fp_line
			(start -0.67945 -0.3048)
			(end -0.67945 0.3048)
			(stroke
				(width 0.1)
				(type default)
			)
			(layer "B.Fab")
		)
		(fp_line
			(start 0.12065 -0.2794)
			(end -0.12065 -0.2794)
			(stroke
				(width 0.1)
				(type default)
			)
			(layer "B.Fab")
		)
		(fp_line
			(start -0.12065 -0.2794)
			(end -0.12065 -0.3048)
			(stroke
				(width 0.1)
				(type default)
			)
			(layer "B.Fab")
		)
		(fp_line
			(start 0.12065 0.2794)
			(end 0.12065 0.3048)
			(stroke
				(width 0.1)
				(type default)
			)
			(layer "B.Fab")
		)
		(fp_line
			(start -0.120396 0.2794)
			(end 0.12065 0.2794)
			(stroke
				(width 0.1)
				(type default)
			)
			(layer "B.Fab")
		)
		(fp_line
			(start 0.67945 0.3048)
			(end 0.67945 -0.305054)
			(stroke
				(width 0.1)
				(type default)
			)
			(layer "B.Fab")
		)
		(fp_line
			(start 0.12065 0.3048)
			(end 0.67945 0.3048)
			(stroke
				(width 0.1)
				(type default)
			)
			(layer "B.Fab")
		)
		(fp_line
			(start -0.120396 0.3048)
			(end -0.120396 0.2794)
			(stroke
				(width 0.1)
				(type default)
			)
			(layer "B.Fab")
		)
		(fp_line
			(start -0.67945 0.3048)
			(end -0.120396 0.3048)
			(stroke
				(width 0.1)
				(type default)
			)
			(layer "B.Fab")
		)
		(pad "1" smd circle
			(at 0.40005 0 270)
			(size 0 0)
			(layers "B.Cu" "B.Mask" "B.Paste")
			(net "P12V_HSC_GATE_RC")
		)
		(pad "2" smd circle
			(at -0.40005 0 270)
			(size 0 0)
			(layers "B.Cu" "B.Mask" "B.Paste")
			(net "P12V_AUX")
		)
	)
	(footprint ""
		(layer "B.Cu")
		(at 13.472668 -284.2514 180)
		(property "Reference" "PC212"
			(at 0 0 0)
			(layer "B.SilkS")
			(hide yes)
			(effects
				(font
					(size 1.27 1.27)
				)
				(justify mirror)
			)
		)
		(property "Value" ""
			(at 0 0 0)
			(layer "B.Fab")
			(effects
				(font
					(size 1.27 1.27)
				)
				(justify mirror)
			)
		)
		(duplicate_pad_numbers_are_jumpers no)
		(fp_line
			(start 1.524 0.762)
			(end 1.524 -0.762)
			(stroke
				(width 0.1524)
				(type default)
			)
			(layer "B.SilkS")
		)
		(fp_line
			(start 1.524 -0.762)
			(end -1.524 -0.762)
			(stroke
				(width 0.1524)
				(type default)
			)
			(layer "B.SilkS")
		)
		(fp_line
			(start -1.524 0.762)
			(end 1.524 0.762)
			(stroke
				(width 0.1524)
				(type default)
			)
			(layer "B.SilkS")
		)
		(fp_line
			(start -1.524 -0.762)
			(end -1.524 0.762)
			(stroke
				(width 0.1524)
				(type default)
			)
			(layer "B.SilkS")
		)
		(fp_line
			(start 1.1049 0.724916)
			(end -1.1049 0.724916)
			(stroke
				(width 0.1)
				(type default)
			)
			(layer "B.Fab")
		)
		(fp_line
			(start 1.1049 -0.724916)
			(end 1.1049 0.724916)
			(stroke
				(width 0.1)
				(type default)
			)
			(layer "B.Fab")
		)
		(fp_line
			(start -1.1049 0.724916)
			(end -1.1049 -0.724916)
			(stroke
				(width 0.1)
				(type default)
			)
			(layer "B.Fab")
		)
		(fp_line
			(start -1.1049 -0.724916)
			(end 1.1049 -0.724916)
			(stroke
				(width 0.1)
				(type default)
			)
			(layer "B.Fab")
		)
		(pad "1" smd rect
			(at 0.889 0 180)
			(size 1.016 1.27)
			(layers "B.Cu" "B.Mask" "B.Paste")
			(net "P1V25_PEX0_R")
		)
		(pad "2" smd rect
			(at -0.889 0 180)
			(size 1.016 1.27)
			(layers "B.Cu" "B.Mask" "B.Paste")
			(net "GND")
		)
	)
	(footprint ""
		(layer "B.Cu")
		(at 60.599828 -301.599854 -90)
		(property "Reference" "C1226"
			(at 0 0 90)
			(layer "B.SilkS")
			(hide yes)
			(effects
				(font
					(size 1.27 1.27)
				)
				(justify mirror)
			)
		)
		(property "Value" ""
			(at 0 0 90)
			(layer "B.Fab")
			(effects
				(font
					(size 1.27 1.27)
				)
				(justify mirror)
			)
		)
		(duplicate_pad_numbers_are_jumpers no)
		(fp_line
			(start -0.299974 0.150114)
			(end 0.299974 0.150114)
			(stroke
				(width 0.1)
				(type default)
			)
			(layer "B.Fab")
		)
		(fp_line
			(start 0.299974 0.150114)
			(end 0.299974 -0.150114)
			(stroke
				(width 0.1)
				(type default)
			)
			(layer "B.Fab")
		)
		(fp_line
			(start -0.299974 -0.150114)
			(end -0.299974 0.150114)
			(stroke
				(width 0.1)
				(type default)
			)
			(layer "B.Fab")
		)
		(fp_line
			(start 0.299974 -0.150114)
			(end -0.299974 -0.150114)
			(stroke
				(width 0.1)
				(type default)
			)
			(layer "B.Fab")
		)
		(pad "1" smd rect
			(at 0.2667 0 90)
			(size 0.3048 0.381)
			(layers "B.Cu" "B.Mask" "B.Paste")
			(net "P0V8_SERDES_VDDA_PEX0")
		)
		(pad "2" smd rect
			(at -0.2667 0 90)
			(size 0.3048 0.381)
			(layers "B.Cu" "B.Mask" "B.Paste")
			(net "GND")
		)
	)
	(footprint ""
		(layer "B.Cu")
		(at 24.711406 -222.299276 180)
		(property "Reference" "C2217"
			(at 0 0 0)
			(layer "B.SilkS")
			(hide yes)
			(effects
				(font
					(size 1.27 1.27)
				)
				(justify mirror)
			)
		)
		(property "Value" ""
			(at 0 0 0)
			(layer "B.Fab")
			(effects
				(font
					(size 1.27 1.27)
				)
				(justify mirror)
			)
		)
		(duplicate_pad_numbers_are_jumpers no)
		(fp_line
			(start 0.7874 0.4064)
			(end 0.7874 -0.4064)
			(stroke
				(width 0.1524)
				(type default)
			)
			(layer "B.SilkS")
		)
		(fp_line
			(start 0.7874 -0.4064)
			(end -0.7874 -0.4064)
			(stroke
				(width 0.1524)
				(type default)
			)
			(layer "B.SilkS")
		)
		(fp_line
			(start -0.7874 0.4064)
			(end 0.7874 0.4064)
			(stroke
				(width 0.1524)
				(type default)
			)
			(layer "B.SilkS")
		)
		(fp_line
			(start -0.7874 -0.4064)
			(end -0.7874 0.4064)
			(stroke
				(width 0.1524)
				(type default)
			)
			(layer "B.SilkS")
		)
		(fp_line
			(start 0.67945 0.3048)
			(end 0.67945 -0.305054)
			(stroke
				(width 0.1)
				(type default)
			)
			(layer "B.Fab")
		)
		(fp_line
			(start 0.67945 -0.305054)
			(end 0.12065 -0.305054)
			(stroke
				(width 0.1)
				(type default)
			)
			(layer "B.Fab")
		)
		(fp_line
			(start 0.12065 0.3048)
			(end 0.67945 0.3048)
			(stroke
				(width 0.1)
				(type default)
			)
			(layer "B.Fab")
		)
		(fp_line
			(start 0.12065 0.2794)
			(end 0.12065 0.3048)
			(stroke
				(width 0.1)
				(type default)
			)
			(layer "B.Fab")
		)
		(fp_line
			(start 0.12065 -0.2794)
			(end -0.12065 -0.2794)
			(stroke
				(width 0.1)
				(type default)
			)
			(layer "B.Fab")
		)
		(fp_line
			(start 0.12065 -0.305054)
			(end 0.12065 -0.2794)
			(stroke
				(width 0.1)
				(type default)
			)
			(layer "B.Fab")
		)
		(fp_line
			(start -0.120396 0.3048)
			(end -0.120396 0.2794)
			(stroke
				(width 0.1)
				(type default)
			)
			(layer "B.Fab")
		)
		(fp_line
			(start -0.120396 0.2794)
			(end 0.12065 0.2794)
			(stroke
				(width 0.1)
				(type default)
			)
			(layer "B.Fab")
		)
		(fp_line
			(start -0.12065 -0.2794)
			(end -0.12065 -0.3048)
			(stroke
				(width 0.1)
				(type default)
			)
			(layer "B.Fab")
		)
		(fp_line
			(start -0.12065 -0.3048)
			(end -0.67945 -0.3048)
			(stroke
				(width 0.1)
				(type default)
			)
			(layer "B.Fab")
		)
		(fp_line
			(start -0.67945 0.3048)
			(end -0.120396 0.3048)
			(stroke
				(width 0.1)
				(type default)
			)
			(layer "B.Fab")
		)
		(fp_line
			(start -0.67945 -0.3048)
			(end -0.67945 0.3048)
			(stroke
				(width 0.1)
				(type default)
			)
			(layer "B.Fab")
		)
		(pad "1" smd circle
			(at 0.40005 0)
			(size 0 0)
			(layers "B.Cu" "B.Mask" "B.Paste")
			(net "GND")
		)
		(pad "2" smd circle
			(at -0.40005 0)
			(size 0 0)
			(layers "B.Cu" "B.Mask" "B.Paste")
			(net "P1V8_PEX")
		)
	)
	(footprint ""
		(layer "B.Cu")
		(at 69.624956 -305.608228 -90)
		(property "Reference" "C2998"
			(at 0 0 90)
			(layer "B.SilkS")
			(hide yes)
			(effects
				(font
					(size 1.27 1.27)
				)
				(justify mirror)
			)
		)
		(property "Value" ""
			(at 0 0 90)
			(layer "B.Fab")
			(effects
				(font
					(size 1.27 1.27)
				)
				(justify mirror)
			)
		)
		(duplicate_pad_numbers_are_jumpers no)
		(fp_line
			(start -0.299974 0.150114)
			(end 0.299974 0.150114)
			(stroke
				(width 0.1)
				(type default)
			)
			(layer "B.Fab")
		)
		(fp_line
			(start 0.299974 0.150114)
			(end 0.299974 -0.150114)
			(stroke
				(width 0.1)
				(type default)
			)
			(layer "B.Fab")
		)
		(fp_line
			(start -0.299974 -0.150114)
			(end -0.299974 0.150114)
			(stroke
				(width 0.1)
				(type default)
			)
			(layer "B.Fab")
		)
		(fp_line
			(start 0.299974 -0.150114)
			(end -0.299974 -0.150114)
			(stroke
				(width 0.1)
				(type default)
			)
			(layer "B.Fab")
		)
		(pad "1" smd rect
			(at 0.2667 0 90)
			(size 0.3048 0.381)
			(layers "B.Cu" "B.Mask" "B.Paste")
			(net "P1V8_VDDA_PEX0")
		)
		(pad "2" smd rect
			(at -0.2667 0 90)
			(size 0.3048 0.381)
			(layers "B.Cu" "B.Mask" "B.Paste")
			(net "GND")
		)
	)
	(footprint ""
		(layer "B.Cu")
		(at 128.241044 -180.02377)
		(property "Reference" "R1124"
			(at 0 0 0)
			(layer "B.SilkS")
			(hide yes)
			(effects
				(font
					(size 1.27 1.27)
				)
				(justify mirror)
			)
		)
		(property "Value" ""
			(at 0 0 0)
			(layer "B.Fab")
			(effects
				(font
					(size 1.27 1.27)
				)
				(justify mirror)
			)
		)
		(duplicate_pad_numbers_are_jumpers no)
		(fp_line
			(start -0.7874 -0.4064)
			(end -0.7874 0.4064)
			(stroke
				(width 0.1524)
				(type default)
			)
			(layer "B.SilkS")
		)
		(fp_line
			(start -0.7874 0.4064)
			(end 0.7874 0.4064)
			(stroke
				(width 0.1524)
				(type default)
			)
			(layer "B.SilkS")
		)
		(fp_line
			(start 0.7874 -0.4064)
			(end -0.7874 -0.4064)
			(stroke
				(width 0.1524)
				(type default)
			)
			(layer "B.SilkS")
		)
		(fp_line
			(start 0.7874 0.4064)
			(end 0.7874 -0.4064)
			(stroke
				(width 0.1524)
				(type default)
			)
			(layer "B.SilkS")
		)
		(fp_line
			(start -0.67945 -0.3048)
			(end -0.67945 0.3048)
			(stroke
				(width 0.1)
				(type default)
			)
			(layer "B.Fab")
		)
		(fp_line
			(start -0.67945 0.3048)
			(end -0.120396 0.3048)
			(stroke
				(width 0.1)
				(type default)
			)
			(layer "B.Fab")
		)
		(fp_line
			(start -0.12065 -0.3048)
			(end -0.67945 -0.3048)
			(stroke
				(width 0.1)
				(type default)
			)
			(layer "B.Fab")
		)
		(fp_line
			(start -0.12065 -0.2794)
			(end -0.12065 -0.3048)
			(stroke
				(width 0.1)
				(type default)
			)
			(layer "B.Fab")
		)
		(fp_line
			(start -0.120396 0.2794)
			(end 0.12065 0.2794)
			(stroke
				(width 0.1)
				(type default)
			)
			(layer "B.Fab")
		)
		(fp_line
			(start -0.120396 0.3048)
			(end -0.120396 0.2794)
			(stroke
				(width 0.1)
				(type default)
			)
			(layer "B.Fab")
		)
		(fp_line
			(start 0.12065 -0.305054)
			(end 0.12065 -0.2794)
			(stroke
				(width 0.1)
				(type default)
			)
			(layer "B.Fab")
		)
		(fp_line
			(start 0.12065 -0.2794)
			(end -0.12065 -0.2794)
			(stroke
				(width 0.1)
				(type default)
			)
			(layer "B.Fab")
		)
		(fp_line
			(start 0.12065 0.2794)
			(end 0.12065 0.3048)
			(stroke
				(width 0.1)
				(type default)
			)
			(layer "B.Fab")
		)
		(fp_line
			(start 0.12065 0.3048)
			(end 0.67945 0.3048)
			(stroke
				(width 0.1)
				(type default)
			)
			(layer "B.Fab")
		)
		(fp_line
			(start 0.67945 -0.305054)
			(end 0.12065 -0.305054)
			(stroke
				(width 0.1)
				(type default)
			)
			(layer "B.Fab")
		)
		(fp_line
			(start 0.67945 0.3048)
			(end 0.67945 -0.305054)
			(stroke
				(width 0.1)
				(type default)
			)
			(layer "B.Fab")
		)
		(pad "1" smd circle
			(at 0.40005 0 180)
			(size 0 0)
			(layers "B.Cu" "B.Mask" "B.Paste")
			(net "FM_DB2000QL_VSBEN")
		)
		(pad "2" smd circle
			(at -0.40005 0 180)
			(size 0 0)
			(layers "B.Cu" "B.Mask" "B.Paste")
			(net "P3V3")
		)
	)
	(footprint ""
		(layer "B.Cu")
		(at 180.975 -293.99992 90)
		(property "Reference" "C1409"
			(at 0 0 90)
			(layer "B.SilkS")
			(hide yes)
			(effects
				(font
					(size 1.27 1.27)
				)
				(justify mirror)
			)
		)
		(property "Value" ""
			(at 0 0 90)
			(layer "B.Fab")
			(effects
				(font
					(size 1.27 1.27)
				)
				(justify mirror)
			)
		)
		(duplicate_pad_numbers_are_jumpers no)
		(fp_line
			(start 0.299974 -0.150114)
			(end -0.299974 -0.150114)
			(stroke
				(width 0.1)
				(type default)
			)
			(layer "B.Fab")
		)
		(fp_line
			(start -0.299974 -0.150114)
			(end -0.299974 0.150114)
			(stroke
				(width 0.1)
				(type default)
			)
			(layer "B.Fab")
		)
		(fp_line
			(start 0.299974 0.150114)
			(end 0.299974 -0.150114)
			(stroke
				(width 0.1)
				(type default)
			)
			(layer "B.Fab")
		)
		(fp_line
			(start -0.299974 0.150114)
			(end 0.299974 0.150114)
			(stroke
				(width 0.1)
				(type default)
			)
			(layer "B.Fab")
		)
		(pad "1" smd rect
			(at 0.2667 0 270)
			(size 0.3048 0.381)
			(layers "B.Cu" "B.Mask" "B.Paste")
			(net "P0V8_PEX1")
		)
		(pad "2" smd rect
			(at -0.2667 0 270)
			(size 0.3048 0.381)
			(layers "B.Cu" "B.Mask" "B.Paste")
			(net "GND")
		)
	)
)
